# S9S_MB_2U (Grand Teton) — schematic netlist excerpt (pin names and nets, part order shuffled) for the footprints in the layout excerpt that follows; sources: Cadence DE-HDL packaged netlist, KiCad conversion of 03242023_DA0F0TMBIJ0_F0T_Motherboard_J_brd_V01_OCP.brd

R156  Q_RES  100 1% CHIP  pkg 0402LF  page 125 : A = PWRGD_CPU1_BUF_R ; B = PWRGD_CPU1_LVC1
C543  Q_CAP  0.1UF 25V 10% X7R  pkg 0402  page 133 : A = P3V3_AUX ; B = GND

(kicad_pcb
	(version 20260206)
	(generator "pcbnew")
	(generator_version "10.0")
	(general
		(thickness 1.6)
		(legacy_teardrops no)
	)
	(paper "A4")
	(title_block
		(title "03242023_DA0F0TMBIJ0_F0T_Motherboard_J_brd_V01_OCP.brd")
		(comment 1 "Grand Teton / footprints 5947-5948 of 6105")
	)
	(layers
		(0 "F.Cu" signal "TOP")
		(4 "In1.Cu" signal "GND")
		(6 "In2.Cu" signal "IN1")
		(8 "In3.Cu" signal "GND1")
		(10 "In4.Cu" signal "IN2")
		(12 "In5.Cu" signal "GND2")
		(14 "In6.Cu" signal "IN3")
		(16 "In7.Cu" signal "GND3")
		(18 "In8.Cu" signal "VCC")
		(20 "In9.Cu" signal "VCC1")
		(22 "In10.Cu" signal "GND4")
		(24 "In11.Cu" signal "IN4")
		(26 "In12.Cu" signal "GND5")
		(28 "In13.Cu" signal "IN5")
		(30 "In14.Cu" signal "GND6")
		(32 "In15.Cu" signal "IN6")
		(34 "In16.Cu" signal "GND7")
		(2 "B.Cu" signal "BOTTOM")
		(9 "F.Adhes" user "F.Adhesive")
		(11 "B.Adhes" user "B.Adhesive")
		(13 "F.Paste" user "Package Geometry/Pastemask Top")
		(15 "B.Paste" user "Package Geometry/Pastemask Bottom")
		(5 "F.SilkS" user "Ref Des/Silkscreen Top")
		(7 "B.SilkS" user "Ref Des/Silkscreen Bottom")
		(1 "F.Mask" user "Board Geometry/Soldermask Top")
		(3 "B.Mask" user "Board Geometry/Soldermask Bottom")
		(17 "Dwgs.User" user "User.Drawings")
		(19 "Cmts.User" user "User.Comments")
		(21 "Eco1.User" user "User.Eco1")
		(23 "Eco2.User" user "User.Eco2")
		(25 "Edge.Cuts" user "Board Geometry/Outline")
		(27 "Margin" user)
		(31 "F.CrtYd" user "Package Geometry/Place Bound Top")
		(29 "B.CrtYd" user "Package Geometry/Place Bound Bottom")
		(35 "F.Fab" user "Ref Des/Assembly Top")
		(33 "B.Fab" user "Ref Des/Assembly Bottom")
	)
	(footprint ""
		(layer "B.Cu")
		(at 68.337684 -183.303926 -90)
		(property "Reference" "R156"
			(at 0 0 90)
			(layer "B.SilkS")
			(hide yes)
			(effects
				(font
					(size 1.27 1.27)
				)
				(justify mirror)
			)
		)
		(property "Value" ""
			(at 0 0 90)
			(layer "B.Fab")
			(effects
				(font
					(size 1.27 1.27)
				)
				(justify mirror)
			)
		)
		(duplicate_pad_numbers_are_jumpers no)
		(fp_line
			(start -0.7874 0.4064)
			(end 0.7874 0.4064)
			(stroke
				(width 0.1524)
				(type default)
			)
			(layer "B.SilkS")
		)
		(fp_line
			(start 0.7874 0.4064)
			(end 0.7874 -0.4064)
			(stroke
				(width 0.1524)
				(type default)
			)
			(layer "B.SilkS")
		)
		(fp_line
			(start -0.7874 -0.4064)
			(end -0.7874 0.4064)
			(stroke
				(width 0.1524)
				(type default)
			)
			(layer "B.SilkS")
		)
		(fp_line
			(start 0.7874 -0.4064)
			(end -0.7874 -0.4064)
			(stroke
				(width 0.1524)
				(type default)
			)
			(layer "B.SilkS")
		)
		(fp_line
			(start -0.67945 0.3048)
			(end -0.120396 0.3048)
			(stroke
				(width 0.1)
				(type default)
			)
			(layer "B.Fab")
		)
		(fp_line
			(start -0.120396 0.3048)
			(end -0.120396 0.2794)
			(stroke
				(width 0.1)
				(type default)
			)
			(layer "B.Fab")
		)
		(fp_line
			(start 0.12065 0.3048)
			(end 0.67945 0.3048)
			(stroke
				(width 0.1)
				(type default)
			)
			(layer "B.Fab")
		)
		(fp_line
			(start 0.67945 0.3048)
			(end 0.67945 -0.305054)
			(stroke
				(width 0.1)
				(type default)
			)
			(layer "B.Fab")
		)
		(fp_line
			(start -0.120396 0.2794)
			(end 0.12065 0.2794)
			(stroke
				(width 0.1)
				(type default)
			)
			(layer "B.Fab")
		)
		(fp_line
			(start 0.12065 0.2794)
			(end 0.12065 0.3048)
			(stroke
				(width 0.1)
				(type default)
			)
			(layer "B.Fab")
		)
		(fp_line
			(start -0.12065 -0.2794)
			(end -0.12065 -0.3048)
			(stroke
				(width 0.1)
				(type default)
			)
			(layer "B.Fab")
		)
		(fp_line
			(start 0.12065 -0.2794)
			(end -0.12065 -0.2794)
			(stroke
				(width 0.1)
				(type default)
			)
			(layer "B.Fab")
		)
		(fp_line
			(start -0.67945 -0.3048)
			(end -0.67945 0.3048)
			(stroke
				(width 0.1)
				(type default)
			)
			(layer "B.Fab")
		)
		(fp_line
			(start -0.12065 -0.3048)
			(end -0.67945 -0.3048)
			(stroke
				(width 0.1)
				(type default)
			)
			(layer "B.Fab")
		)
		(fp_line
			(start 0.12065 -0.305054)
			(end 0.12065 -0.2794)
			(stroke
				(width 0.1)
				(type default)
			)
			(layer "B.Fab")
		)
		(fp_line
			(start 0.67945 -0.305054)
			(end 0.12065 -0.305054)
			(stroke
				(width 0.1)
				(type default)
			)
			(layer "B.Fab")
		)
		(pad "1" smd circle
			(at 0.40005 0 90)
			(size 0 0)
			(layers "B.Cu" "B.Mask" "B.Paste")
			(net "PWRGD_CPU1_BUF_R")
		)
		(pad "2" smd circle
			(at -0.40005 0 90)
			(size 0 0)
			(layers "B.Cu" "B.Mask" "B.Paste")
			(net "PWRGD_CPU1_LVC1")
		)
	)
	(footprint ""
		(layer "B.Cu")
		(at 194.159378 -193.43497)
		(property "Reference" "C543"
			(at 0 0 0)
			(layer "B.SilkS")
			(hide yes)
			(effects
				(font
					(size 1.27 1.27)
				)
				(justify mirror)
			)
		)
		(property "Value" ""
			(at 0 0 0)
			(layer "B.Fab")
			(effects
				(font
					(size 1.27 1.27)
				)
				(justify mirror)
			)
		)
		(duplicate_pad_numbers_are_jumpers no)
		(fp_line
			(start -0.7874 -0.4064)
			(end -0.7874 0.4064)
			(stroke
				(width 0.1524)
				(type default)
			)
			(layer "B.SilkS")
		)
		(fp_line
			(start -0.7874 0.4064)
			(end 0.7874 0.4064)
			(stroke
				(width 0.1524)
				(type default)
			)
			(layer "B.SilkS")
		)
		(fp_line
			(start 0.7874 -0.4064)
			(end -0.7874 -0.4064)
			(stroke
				(width 0.1524)
				(type default)
			)
			(layer "B.SilkS")
		)
		(fp_line
			(start 0.7874 0.4064)
			(end 0.7874 -0.4064)
			(stroke
				(width 0.1524)
				(type default)
			)
			(layer "B.SilkS")
		)
		(fp_line
			(start -0.67945 -0.3048)
			(end -0.67945 0.3048)
			(stroke
				(width 0.1)
				(type default)
			)
			(layer "B.Fab")
		)
		(fp_line
			(start -0.67945 0.3048)
			(end -0.120396 0.3048)
			(stroke
				(width 0.1)
				(type default)
			)
			(layer "B.Fab")
		)
		(fp_line
			(start -0.12065 -0.3048)
			(end -0.67945 -0.3048)
			(stroke
				(width 0.1)
				(type default)
			)
			(layer "B.Fab")
		)
		(fp_line
			(start -0.12065 -0.2794)
			(end -0.12065 -0.3048)
			(stroke
				(width 0.1)
				(type default)
			)
			(layer "B.Fab")
		)
		(fp_line
			(start -0.120396 0.2794)
			(end 0.12065 0.2794)
			(stroke
				(width 0.1)
				(type default)
			)
			(layer "B.Fab")
		)
		(fp_line
			(start -0.120396 0.3048)
			(end -0.120396 0.2794)
			(stroke
				(width 0.1)
				(type default)
			)
			(layer "B.Fab")
		)
		(fp_line
			(start 0.12065 -0.305054)
			(end 0.12065 -0.2794)
			(stroke
				(width 0.1)
				(type default)
			)
			(layer "B.Fab")
		)
		(fp_line
			(start 0.12065 -0.2794)
			(end -0.12065 -0.2794)
			(stroke
				(width 0.1)
				(type default)
			)
			(layer "B.Fab")
		)
		(fp_line
			(start 0.12065 0.2794)
			(end 0.12065 0.3048)
			(stroke
				(width 0.1)
				(type default)
			)
			(layer "B.Fab")
		)
		(fp_line
			(start 0.12065 0.3048)
			(end 0.67945 0.3048)
			(stroke
				(width 0.1)
				(type default)
			)
			(layer "B.Fab")
		)
		(fp_line
			(start 0.67945 -0.305054)
			(end 0.12065 -0.305054)
			(stroke
				(width 0.1)
				(type default)
			)
			(layer "B.Fab")
		)
		(fp_line
			(start 0.67945 0.3048)
			(end 0.67945 -0.305054)
			(stroke
				(width 0.1)
				(type default)
			)
			(layer "B.Fab")
		)
		(pad "1" smd circle
			(at 0.40005 0 180)
			(size 0 0)
			(layers "B.Cu" "B.Mask" "B.Paste")
			(net "P3V3_AUX")
		)
		(pad "2" smd circle
			(at -0.40005 0 180)
			(size 0 0)
			(layers "B.Cu" "B.Mask" "B.Paste")
			(net "GND")
		)
	)
)
